#ISCELL
  mstr_misc prelim *
  *
#ISCELL
  mstr_symbols design_note *
  *
#ISCELL
  mstr_symbols intel_corp_bpage *
  *
#ISCELL
  mstr_symbols gnd *
  page40_i11
#ISCELL
  mstr_symbols gnd *
  page40_i13
#ISCELL
  mstr_symbols gnd *
  page40_i14
#CELL
  chpset_lib skx_ext_b *
  page40_i20
#CELL
  chpset_lib skx_ext_b *
  page40_i21
#CELL
  chpset_lib skx_ext_b *
  page40_i22
#CELL
  chpset_lib skx_ext_b *
  page40_i23
#ISCELL
  mstr_symbols gnd *
  page40_i3
#ISCELL
  mstr_symbols gnd *
  page40_i4
#ISCELL
  mstr_symbols gnd *
  page40_i5
#ISCELL
  mstr_symbols gnd *
  page40_i6
#ISCELL
  mstr_symbols gnd *
  page40_i9
